(kicad_pcb
	(version 20221018)
	(generator pcbnew)
	(general
    (thickness 1.518)
  )
	(paper "A4")
	(title_block
    (title "Kria K26 Devboard")
    (date "2024-03-26")
    (rev "1.2.5")
    (comment 1 "www.antmicro.com")
    (comment 2 "Antmicro Ltd.")
		(comment 9 "footprints 16-25 of 660")
	)
	(layers
    (0 "F.Cu" mixed)
    (1 "In1.Cu" power)
    (2 "In2.Cu" mixed)
    (3 "In3.Cu" power)
    (4 "In4.Cu" mixed)
    (5 "In5.Cu" power)
    (6 "In6.Cu" mixed)
    (31 "B.Cu" power)
    (32 "B.Adhes" user "B.Adhesive")
    (33 "F.Adhes" user "F.Adhesive")
    (34 "B.Paste" user)
    (35 "F.Paste" user)
    (36 "B.SilkS" user "B.Silkscreen")
    (37 "F.SilkS" user "F.Silkscreen")
    (38 "B.Mask" user)
    (39 "F.Mask" user)
    (40 "Dwgs.User" user "User.Drawings")
    (41 "Cmts.User" user "User.Comments")
    (42 "Eco1.User" user "User.Eco1")
    (43 "Eco2.User" user "User.Eco2")
    (44 "Edge.Cuts" user)
    (45 "Margin" user)
    (46 "B.CrtYd" user "B.Courtyard")
    (47 "F.CrtYd" user "F.Courtyard")
    (48 "B.Fab" user)
    (49 "F.Fab" user)
  )
	(footprint "kria-k26-devboard-footprints:oshw-logo"
		(layer "F.Cu")
    (at 78.175 68.6)
    (descr "OSHW Logo")
    (tags "OSHW Logo")
    (property "Author" "Antmicro")
    (property "License" "Apache-2.0")
    (property "MPN" "")
    (property "Manufacturer" "")
    (property "Sheetfile" "kria-k26-devboard.kicad_sch")
    (property "Sheetname" "")
    (attr exclude_from_pos_files)
    (fp_text reference "N2" (at 0 -4.4) (layer "F.SilkS") hide
        (effects (font (size 0.7 0.7) (thickness 0.15)) (justify left bottom))
    )
    (fp_text value "oshw_logo" (at 0 -3.4) (layer "F.Fab") hide
        (effects (font (size 0.7 0.7) (thickness 0.15)) (justify left bottom))
    )
  )
	(footprint "kria-k26-devboard-footprints:CONV_PDQE30-Q48-S5-D" (layer "F.Cu")
    (at 187.658 90.642 -90)
    (property "Author" "Antmicro")
    (property "License" "Apache-2.0")
    (property "MPN" "PDQE30-Q48-S12-D")
    (property "Manufacturer" "CUI Inc")
    (property "Sheetfile" "PoE.kicad_sch")
    (property "Sheetname" "PoE")
    (property "ki_description" "Isolated Through Hole DC/DC Converter, ITE, 4:1, 30 W, 1 Output, 12 V, 2.5 A")
    (property "ki_keywords" "THT, PMIC, IC, DC-DC, CONVERTER")
    (attr through_hole)
    (fp_text reference "PS1" (at 0 -3.726 -90) (layer "F.SilkS")
        (effects (font (size 0.7 0.7) (thickness 0.15)) (justify left bottom))
    )
    (fp_text value "PDQE30-Q48-S12-D" (at 10.32 24.312 -90) (layer "F.Fab") hide
        (effects (font (size 0.7 0.7) (thickness 0.15)) (justify left bottom))
    )
    (fp_text user "Author: Antmicro" (at -3.912 26.312 -90) (layer "F.Fab") hide
        (effects (font (size 0.7 0.7) (thickness 0.15)) (justify left bottom))
    )
    (fp_text user "License: Apache-2.0" (at -3.912 27.51 -90) (layer "F.Fab") hide
        (effects (font (size 0.7 0.7) (thickness 0.15)) (justify left bottom))
    )
    (fp_text user "${REFERENCE}" (at -3.912 28.711 -90) (layer "F.Fab") hide
        (effects (font (size 0.7 0.7) (thickness 0.15)) (justify left bottom))
    )
    (fp_line (start -2.54 -2.54) (end 22.859 -2.54)
      (stroke (width 0.15) (type solid)) (layer "F.SilkS"))
    (fp_line (start -2.54 22.859) (end -2.54 -2.54)
      (stroke (width 0.15) (type solid)) (layer "F.SilkS"))
    (fp_line (start 22.859 -2.54) (end 22.859 22.859)
      (stroke (width 0.15) (type solid)) (layer "F.SilkS"))
    (fp_line (start 22.859 22.859) (end -2.54 22.859)
      (stroke (width 0.15) (type solid)) (layer "F.SilkS"))
    (fp_circle (center -2.921 0) (end -2.82 0)
      (stroke (width 0.15) (type solid)) (fill none) (layer "F.SilkS"))
    (fp_circle (center 0 -3.84) (end 0.05 -3.84)
      (stroke (width 0.15) (type solid)) (fill solid) (layer "F.SilkS"))
    (fp_circle (center 0 -3.84) (end 0.05 -3.84)
      (stroke (width 0.15) (type solid)) (fill solid) (layer "F.SilkS"))
    (fp_rect (start -2.667 -2.667) (end 22.987 22.987)
      (stroke (width 0.05) (type solid)) (fill none) (layer "F.CrtYd"))
    (fp_line (start -2.54 -2.54) (end 22.859 -2.54)
      (stroke (width 0.15) (type solid)) (layer "F.Fab"))
    (fp_line (start -2.54 22.859) (end -2.54 -2.54)
      (stroke (width 0.15) (type solid)) (layer "F.Fab"))
    (fp_line (start 22.859 -2.54) (end 22.859 22.859)
      (stroke (width 0.15) (type solid)) (layer "F.Fab"))
    (fp_line (start 22.859 22.859) (end -2.54 22.859)
      (stroke (width 0.15) (type solid)) (layer "F.Fab"))
    (fp_circle (center -2.921 0) (end -2.82 0)
      (stroke (width 0.15) (type solid)) (fill none) (layer "F.Fab"))
    (pad "1" thru_hole rect (at 0 0 270) (size 2.25 2.25) (drill 1.5) (layers "*.Cu" "*.Mask")
      (net 12 "/Power Supply/PoE/POE_ACTIVE") (pinfunction "CTRL") (pintype "input"))
    (pad "2" thru_hole circle (at 0 7.618 270) (size 2.25 2.25) (drill 1.5) (layers "*.Cu" "*.Mask")
      (net 11 "GNDD") (pinfunction "GND") (pintype "power_in"))
    (pad "3" thru_hole circle (at 0 12.698 270) (size 2.25 2.25) (drill 1.5) (layers "*.Cu" "*.Mask")
      (net 9 "/Power Supply/PoE/VDD_POE_IN") (pinfunction "V_{IN}") (pintype "power_in"))
    (pad "4" thru_hole circle (at 20.318 20.318 270) (size 2.25 2.25) (drill 1.5) (layers "*.Cu" "*.Mask")
      (net 13 "/Power Supply/PoE/POE_12V") (pinfunction "V_{O}") (pintype "power_out"))
    (pad "5" thru_hole circle (at 20.318 10.159 270) (size 2.25 2.25) (drill 1.5) (layers "*.Cu" "*.Mask")
      (net 414 "unconnected-(PS1-TRIM-Pad5)") (pinfunction "TRIM") (pintype "passive+no_connect"))
    (pad "6" thru_hole circle (at 20.318 0 270) (size 2.25 2.25) (drill 1.5) (layers "*.Cu" "*.Mask")
      (net 1 "GND") (pinfunction "0V") (pintype "power_out"))
  )
	(footprint "kria-k26-devboard-footprints:R_0402_1005Metric" (layer "F.Cu")
    (at 154.33 67.55 90)
    (descr "Resistor SMD 0402")
    (tags "resistor SMD 0402")
    (property "Author" "Antmicro")
    (property "License" "Apache-2.0")
    (property "MPN" "CR0402-FX-3300GLF")
    (property "Manufacturer" "Bourns")
    (property "Sheetfile" "eth.kicad_sch")
    (property "Sheetname" "Ethernet")
    (property "Tolerance" "1%")
    (property "Val" "330R")
    (property "ki_description" "330R resistor in 0402 package with 1% tolerance")
    (attr smd)
    (fp_text reference "R77" (at 2.3 0.92 90) (layer "F.SilkS")
        (effects (font (size 0.7 0.7) (thickness 0.15)) (justify left bottom))
    )
    (fp_text value "R_330R_0402" (at 0 1.4 90) (layer "F.Fab") hide
        (effects (font (size 0.7 0.7) (thickness 0.15)) (justify left bottom))
    )
    (fp_text user "${REFERENCE}" (at -0.95 3.168 90) (layer "F.Fab") hide
        (effects (font (size 0.7 0.7) (thickness 0.15)) (justify left bottom))
    )
    (fp_text user "License: Apache-2.0" (at -0.95 5.169 90) (layer "F.Fab") hide
        (effects (font (size 0.7 0.7) (thickness 0.15)) (justify left bottom))
    )
    (fp_text user "Author: Antmicro" (at -0.95 4.169 90) (layer "F.Fab") hide
        (effects (font (size 0.7 0.7) (thickness 0.15)) (justify left bottom))
    )
    (fp_rect (start -0.93 -0.47) (end 0.93 0.47)
      (stroke (width 0.05) (type solid)) (fill none) (layer "F.CrtYd"))
    (fp_rect (start -0.5 -0.25) (end 0.5 0.25)
      (stroke (width 0.15) (type solid)) (fill none) (layer "F.Fab"))
    (pad "1" smd roundrect (at -0.485 0 90) (size 0.59 0.64) (layers "F.Cu" "F.Paste" "F.Mask") (roundrect_rratio 0.25)
      (net 16 "PS_2V5") (pintype "passive"))
    (pad "2" smd roundrect (at 0.485 0 90) (size 0.59 0.64) (layers "F.Cu" "F.Paste" "F.Mask") (roundrect_rratio 0.25)
      (net 350 "Net-(J5-LED_GRN+)") (pintype "passive"))
  )
	(footprint "kria-k26-devboard-footprints:R_0402_1005Metric" (layer "F.Cu")
    (at 153.27 67.57 90)
    (descr "Resistor SMD 0402")
    (tags "resistor SMD 0402")
    (property "Author" "Antmicro")
    (property "License" "Apache-2.0")
    (property "MPN" "CR0402-FX-3300GLF")
    (property "Manufacturer" "Bourns")
    (property "Sheetfile" "eth.kicad_sch")
    (property "Sheetname" "Ethernet")
    (property "Tolerance" "1%")
    (property "Val" "330R")
    (property "ki_description" "330R resistor in 0402 package with 1% tolerance")
    (attr smd)
    (fp_text reference "R78" (at 2.3 0.92 90) (layer "F.SilkS")
        (effects (font (size 0.7 0.7) (thickness 0.15)) (justify left bottom))
    )
    (fp_text value "R_330R_0402" (at 0 1.4 90) (layer "F.Fab") hide
        (effects (font (size 0.7 0.7) (thickness 0.15)) (justify left bottom))
    )
    (fp_text user "License: Apache-2.0" (at -0.95 5.169 90) (layer "F.Fab") hide
        (effects (font (size 0.7 0.7) (thickness 0.15)) (justify left bottom))
    )
    (fp_text user "${REFERENCE}" (at -0.95 3.168 90) (layer "F.Fab") hide
        (effects (font (size 0.7 0.7) (thickness 0.15)) (justify left bottom))
    )
    (fp_text user "Author: Antmicro" (at -0.95 4.169 90) (layer "F.Fab") hide
        (effects (font (size 0.7 0.7) (thickness 0.15)) (justify left bottom))
    )
    (fp_rect (start -0.93 -0.47) (end 0.93 0.47)
      (stroke (width 0.05) (type solid)) (fill none) (layer "F.CrtYd"))
    (fp_rect (start -0.5 -0.25) (end 0.5 0.25)
      (stroke (width 0.15) (type solid)) (fill none) (layer "F.Fab"))
    (pad "1" smd roundrect (at -0.485 0 90) (size 0.59 0.64) (layers "F.Cu" "F.Paste" "F.Mask") (roundrect_rratio 0.25)
      (net 16 "PS_2V5") (pintype "passive"))
    (pad "2" smd roundrect (at 0.485 0 90) (size 0.59 0.64) (layers "F.Cu" "F.Paste" "F.Mask") (roundrect_rratio 0.25)
      (net 352 "Net-(J5-LED_YEL+)") (pintype "passive"))
  )
	(footprint "kria-k26-devboard-footprints:R_0402_1005Metric" (layer "F.Cu")
    (at 122 95.3)
    (descr "Resistor SMD 0402")
    (tags "resistor SMD 0402")
    (property "Author" "Antmicro")
    (property "License" "Apache-2.0")
    (property "MPN" "CR0402-FX-1002GLF")
    (property "Manufacturer" "Bourns")
    (property "Sheetfile" "usb.kicad_sch")
    (property "Sheetname" "USB")
    (property "Tolerance" "1%")
    (property "Val" "10k")
    (property "ki_description" "10k resistor in 0402 package with 1% tolerance")
    (attr smd)
    (fp_text reference "R66" (at 0.84 0.31) (layer "F.SilkS")
        (effects (font (size 0.7 0.7) (thickness 0.15)) (justify left bottom))
    )
    (fp_text value "R_10k_0402" (at 0 1.4) (layer "F.Fab") hide
        (effects (font (size 0.7 0.7) (thickness 0.15)) (justify left bottom))
    )
    (fp_text user "License: Apache-2.0" (at -0.95 5.169) (layer "F.Fab") hide
        (effects (font (size 0.7 0.7) (thickness 0.15)) (justify left bottom))
    )
    (fp_text user "${REFERENCE}" (at -0.95 3.168) (layer "F.Fab") hide
        (effects (font (size 0.7 0.7) (thickness 0.15)) (justify left bottom))
    )
    (fp_text user "Author: Antmicro" (at -0.95 4.169) (layer "F.Fab") hide
        (effects (font (size 0.7 0.7) (thickness 0.15)) (justify left bottom))
    )
    (fp_rect (start -0.93 -0.47) (end 0.93 0.47)
      (stroke (width 0.05) (type solid)) (fill none) (layer "F.CrtYd"))
    (fp_rect (start -0.5 -0.25) (end 0.5 0.25)
      (stroke (width 0.15) (type solid)) (fill none) (layer "F.Fab"))
    (pad "1" smd roundrect (at -0.485 0) (size 0.59 0.64) (layers "F.Cu" "F.Paste" "F.Mask") (roundrect_rratio 0.25)
      (net 8 "SOM_5V0") (pintype "passive"))
    (pad "2" smd roundrect (at 0.485 0) (size 0.59 0.64) (layers "F.Cu" "F.Paste" "F.Mask") (roundrect_rratio 0.25)
      (net 669 "Net-(U23-VBUS)") (pintype "passive"))
  )
	(footprint "kria-k26-devboard-footprints:R_0402_1005Metric" (layer "F.Cu")
    (at 125.69 137.6 180)
    (descr "Resistor SMD 0402")
    (tags "resistor SMD 0402")
    (property "Author" "Antmicro")
    (property "License" "Apache-2.0")
    (property "MPN" "CR0402-FX-1002GLF")
    (property "Manufacturer" "Bourns")
    (property "Sheetfile" "sd-3-card.kicad_sch")
    (property "Sheetname" "SD 3.0 card")
    (property "Tolerance" "1%")
    (property "Val" "10k")
    (property "ki_description" "10k resistor in 0402 package with 1% tolerance")
    (attr smd)
    (fp_text reference "R18" (at 1.11 0.43 180) (layer "F.SilkS")
        (effects (font (size 0.7 0.7) (thickness 0.15)) (justify left bottom))
    )
    (fp_text value "R_10k_0402" (at 0 1.4 180) (layer "F.Fab") hide
        (effects (font (size 0.7 0.7) (thickness 0.15)) (justify left bottom))
    )
    (fp_text user "License: Apache-2.0" (at -0.95 5.169 180) (layer "F.Fab") hide
        (effects (font (size 0.7 0.7) (thickness 0.15)) (justify left bottom))
    )
    (fp_text user "${REFERENCE}" (at -0.95 3.168 180) (layer "F.Fab") hide
        (effects (font (size 0.7 0.7) (thickness 0.15)) (justify left bottom))
    )
    (fp_text user "Author: Antmicro" (at -0.95 4.169 180) (layer "F.Fab") hide
        (effects (font (size 0.7 0.7) (thickness 0.15)) (justify left bottom))
    )
    (fp_rect (start -0.93 -0.47) (end 0.93 0.47)
      (stroke (width 0.05) (type solid)) (fill none) (layer "F.CrtYd"))
    (fp_rect (start -0.5 -0.25) (end 0.5 0.25)
      (stroke (width 0.15) (type solid)) (fill none) (layer "F.Fab"))
    (pad "1" smd roundrect (at -0.485 0 180) (size 0.59 0.64) (layers "F.Cu" "F.Paste" "F.Mask") (roundrect_rratio 0.25)
      (net 17 "PS_1V8") (pintype "passive"))
    (pad "2" smd roundrect (at 0.485 0 180) (size 0.59 0.64) (layers "F.Cu" "F.Paste" "F.Mask") (roundrect_rratio 0.25)
      (net 106 "/SD 3.0 card/MIO45") (pintype "passive"))
  )
	(footprint "kria-k26-devboard-footprints:R_0402_1005Metric" (layer "F.Cu")
    (at 145.625 109.575 180)
    (descr "Resistor SMD 0402")
    (tags "resistor SMD 0402")
    (property "Author" "Antmicro")
    (property "License" "Apache-2.0")
    (property "MPN" "CR0402-FX-1003GLF")
    (property "Manufacturer" "Bourns")
    (property "Sheetfile" "debug.kicad_sch")
    (property "Sheetname" "Debug and JTAG")
    (property "Tolerance" "1%")
    (property "Val" "100k")
    (property "ki_description" "100k resistor in 0402 package with 1% tolerance")
    (attr smd)
    (fp_text reference "R104" (at -0.785 0.465 270) (layer "F.SilkS")
        (effects (font (size 0.7 0.7) (thickness 0.15)) (justify left bottom))
    )
    (fp_text value "R_100k_0402" (at 0 1.4 180) (layer "F.Fab") hide
        (effects (font (size 0.7 0.7) (thickness 0.15)) (justify left bottom))
    )
    (fp_text user "${REFERENCE}" (at -0.95 3.168 180) (layer "F.Fab") hide
        (effects (font (size 0.7 0.7) (thickness 0.15)) (justify left bottom))
    )
    (fp_text user "Author: Antmicro" (at -0.95 4.169 180) (layer "F.Fab") hide
        (effects (font (size 0.7 0.7) (thickness 0.15)) (justify left bottom))
    )
    (fp_text user "License: Apache-2.0" (at -0.95 5.169 180) (layer "F.Fab") hide
        (effects (font (size 0.7 0.7) (thickness 0.15)) (justify left bottom))
    )
    (fp_rect (start -0.93 -0.47) (end 0.93 0.47)
      (stroke (width 0.05) (type solid)) (fill none) (layer "F.CrtYd"))
    (fp_rect (start -0.5 -0.25) (end 0.5 0.25)
      (stroke (width 0.15) (type solid)) (fill none) (layer "F.Fab"))
    (pad "1" smd roundrect (at -0.485 0 180) (size 0.59 0.64) (layers "F.Cu" "F.Paste" "F.Mask") (roundrect_rratio 0.25)
      (net 265 "/Debug and JTAG/USBC_VBUS") (pintype "passive"))
    (pad "2" smd roundrect (at 0.485 0 180) (size 0.59 0.64) (layers "F.Cu" "F.Paste" "F.Mask") (roundrect_rratio 0.25)
      (net 136 "/Debug and JTAG/PD1_SVBUS") (pintype "passive"))
  )
	(footprint "kria-k26-devboard-footprints:R_0603_1608Metric" (layer "F.Cu")
    (at 143.4 109.575 180)
    (descr "Resistor SMD 0603")
    (tags "resistor SMD 0603")
    (property "Author" "Antmicro")
    (property "License" "Apache-2.0")
    (property "MPN" "CR0603-FX-1502ELF")
    (property "Manufacturer" "Bourns")
    (property "Sheetfile" "debug.kicad_sch")
    (property "Sheetname" "Debug and JTAG")
    (property "Tolerance" "1%")
    (property "Val" "15k")
    (property "ki_description" "15k resistor in 0603 package with 1% tolerance")
    (attr smd)
    (fp_text reference "R105" (at 1.89 1.825 180) (layer "F.SilkS")
        (effects (font (size 0.7 0.7) (thickness 0.15)) (justify left bottom))
    )
    (fp_text value "R_15k_0603" (at 0 1.6 180) (layer "F.Fab") hide
        (effects (font (size 0.7 0.7) (thickness 0.15)) (justify left bottom))
    )
    (fp_text user "${REFERENCE}" (at -1.25 3.898 180) (layer "F.Fab") hide
        (effects (font (size 0.7 0.7) (thickness 0.15)) (justify left bottom))
    )
    (fp_text user "License: Apache-2.0" (at -1.25 5.9 180) (layer "F.Fab") hide
        (effects (font (size 0.7 0.7) (thickness 0.15)) (justify left bottom))
    )
    (fp_text user "Author: Antmicro" (at -1.25 4.9 180) (layer "F.Fab") hide
        (effects (font (size 0.7 0.7) (thickness 0.15)) (justify left bottom))
    )
    (fp_line (start -0.3 -0.3) (end 0.3 -0.3)
      (stroke (width 0.15) (type solid)) (layer "F.SilkS"))
    (fp_line (start -0.3 0.3) (end 0.3 0.3)
      (stroke (width 0.15) (type solid)) (layer "F.SilkS"))
    (fp_rect (start -1.25 -0.7) (end 1.25 0.7)
      (stroke (width 0.05) (type solid)) (fill none) (layer "F.CrtYd"))
    (fp_rect (start -0.8 -0.4) (end 0.8 0.4)
      (stroke (width 0.15) (type solid)) (fill none) (layer "F.Fab"))
    (pad "1" smd roundrect (at -0.7 0 180) (size 0.6 0.8) (layers "F.Cu" "F.Paste" "F.Mask") (roundrect_rratio 0.2)
      (net 136 "/Debug and JTAG/PD1_SVBUS") (pintype "passive"))
    (pad "2" smd roundrect (at 0.7 0 180) (size 0.6 0.8) (layers "F.Cu" "F.Paste" "F.Mask") (roundrect_rratio 0.2)
      (net 1 "GND") (pintype "passive"))
  )
	(footprint "kria-k26-devboard-footprints:R_0402_1005Metric" (layer "F.Cu")
    (at 118.8 118.8 180)
    (descr "Resistor SMD 0402")
    (tags "resistor SMD 0402")
    (property "Author" "Antmicro")
    (property "License" "Apache-2.0")
    (property "MPN" "CR0402-FX-1002GLF")
    (property "Manufacturer" "Bourns")
    (property "Sheetfile" "clock.kicad_sch")
    (property "Sheetname" "Clock distribution")
    (property "Tolerance" "1%")
    (property "Val" "10k")
    (property "ki_description" "10k resistor in 0402 package with 1% tolerance")
    (attr smd)
    (fp_text reference "R19" (at 0.98 0.53 180) (layer "F.SilkS")
        (effects (font (size 0.7 0.7) (thickness 0.15)) (justify left bottom))
    )
    (fp_text value "R_10k_0402" (at 0 1.4 180) (layer "F.Fab") hide
        (effects (font (size 0.7 0.7) (thickness 0.15)) (justify left bottom))
    )
    (fp_text user "License: Apache-2.0" (at -0.95 5.169 180) (layer "F.Fab") hide
        (effects (font (size 0.7 0.7) (thickness 0.15)) (justify left bottom))
    )
    (fp_text user "${REFERENCE}" (at -0.95 3.168 180) (layer "F.Fab") hide
        (effects (font (size 0.7 0.7) (thickness 0.15)) (justify left bottom))
    )
    (fp_text user "Author: Antmicro" (at -0.95 4.169 180) (layer "F.Fab") hide
        (effects (font (size 0.7 0.7) (thickness 0.15)) (justify left bottom))
    )
    (fp_rect (start -0.93 -0.47) (end 0.93 0.47)
      (stroke (width 0.05) (type solid)) (fill none) (layer "F.CrtYd"))
    (fp_rect (start -0.5 -0.25) (end 0.5 0.25)
      (stroke (width 0.15) (type solid)) (fill none) (layer "F.Fab"))
    (pad "1" smd roundrect (at -0.485 0 180) (size 0.59 0.64) (layers "F.Cu" "F.Paste" "F.Mask") (roundrect_rratio 0.25)
      (net 15 "PS_3V3") (pintype "passive"))
    (pad "2" smd roundrect (at 0.485 0 180) (size 0.59 0.64) (layers "F.Cu" "F.Paste" "F.Mask") (roundrect_rratio 0.25)
      (net 429 "Net-(Q3-C)") (pintype "passive"))
  )
	(footprint "kria-k26-devboard-footprints:R_0402_1005Metric" (layer "F.Cu")
    (at 109.35 136.01 90)
    (descr "Resistor SMD 0402")
    (tags "resistor SMD 0402")
    (property "Author" "Antmicro")
    (property "License" "Apache-2.0")
    (property "MPN" "CR0402-FX-1002GLF")
    (property "Manufacturer" "Bourns")
    (property "Sheetfile" "reset.kicad_sch")
    (property "Sheetname" "Reset logic")
    (property "Tolerance" "1%")
    (property "Val" "10k")
    (property "ki_description" "10k resistor in 0402 package with 1% tolerance")
    (attr smd)
    (fp_text reference "R84" (at 0.74 0.35 90) (layer "F.SilkS")
        (effects (font (size 0.7 0.7) (thickness 0.15)) (justify left bottom))
    )
    (fp_text value "R_10k_0402" (at 0 1.4 90) (layer "F.Fab") hide
        (effects (font (size 0.7 0.7) (thickness 0.15)) (justify left bottom))
    )
    (fp_text user "License: Apache-2.0" (at -0.95 5.169 90) (layer "F.Fab") hide
        (effects (font (size 0.7 0.7) (thickness 0.15)) (justify left bottom))
    )
    (fp_text user "Author: Antmicro" (at -0.95 4.169 90) (layer "F.Fab") hide
        (effects (font (size 0.7 0.7) (thickness 0.15)) (justify left bottom))
    )
    (fp_text user "${REFERENCE}" (at -0.95 3.168 90) (layer "F.Fab") hide
        (effects (font (size 0.7 0.7) (thickness 0.15)) (justify left bottom))
    )
    (fp_rect (start -0.93 -0.47) (end 0.93 0.47)
      (stroke (width 0.05) (type solid)) (fill none) (layer "F.CrtYd"))
    (fp_rect (start -0.5 -0.25) (end 0.5 0.25)
      (stroke (width 0.15) (type solid)) (fill none) (layer "F.Fab"))
    (pad "1" smd roundrect (at -0.485 0 90) (size 0.59 0.64) (layers "F.Cu" "F.Paste" "F.Mask") (roundrect_rratio 0.25)
      (net 17 "PS_1V8") (pintype "passive"))
    (pad "2" smd roundrect (at 0.485 0 90) (size 0.59 0.64) (layers "F.Cu" "F.Paste" "F.Mask") (roundrect_rratio 0.25)
      (net 151 "/Debug and JTAG/~{PS_POR}") (pintype "passive"))
  )
)
